(kicad_pcb
	(version 20260206)
	(generator "pcbnew")
	(generator_version "10.0")
	(general
		(thickness 1.6)
		(legacy_teardrops no)
	)
	(paper "A4")
	(title_block
		(title "01162023_DA0F0TEBIF0_F0T_Expander_BD_F_brd_V02_OCP.brd")
		(comment 1 "Grand Teton / footprints 2838-2843 of 9728")
	)
	(layers
		(0 "F.Cu" signal "TOP")
		(4 "In1.Cu" signal "GND")
		(6 "In2.Cu" signal "VCC")
		(8 "In3.Cu" signal "VCC1")
		(10 "In4.Cu" signal "GND1")
		(12 "In5.Cu" signal "IN1")
		(14 "In6.Cu" signal "GND2")
		(16 "In7.Cu" signal "IN2")
		(18 "In8.Cu" signal "GND3")
		(20 "In9.Cu" signal "IN3")
		(22 "In10.Cu" signal "GND4")
		(24 "In11.Cu" signal "IN4")
		(26 "In12.Cu" signal "GND5")
		(28 "In13.Cu" signal "IN5")
		(30 "In14.Cu" signal "GND6")
		(32 "In15.Cu" signal "IN6")
		(34 "In16.Cu" signal "GND7")
		(2 "B.Cu" signal "BOTTOM")
		(9 "F.Adhes" user "F.Adhesive")
		(11 "B.Adhes" user "B.Adhesive")
		(13 "F.Paste" user "Package Geometry/Pastemask Top")
		(15 "B.Paste" user "Package Geometry/Pastemask Bottom")
		(5 "F.SilkS" user "Ref Des/Silkscreen Top")
		(7 "B.SilkS" user "Ref Des/Silkscreen Bottom")
		(1 "F.Mask" user "Board Geometry/Soldermask Top")
		(3 "B.Mask" user "Board Geometry/Soldermask Bottom")
		(17 "Dwgs.User" user "User.Drawings")
		(19 "Cmts.User" user "User.Comments")
		(21 "Eco1.User" user "User.Eco1")
		(23 "Eco2.User" user "User.Eco2")
		(25 "Edge.Cuts" user "Board Geometry/Outline")
		(27 "Margin" user)
		(31 "F.CrtYd" user "Package Geometry/Place Bound Top")
		(29 "B.CrtYd" user "Package Geometry/Place Bound Bottom")
		(35 "F.Fab" user "Ref Des/Assembly Top")
		(33 "B.Fab" user "Ref Des/Assembly Bottom")
	)
	(footprint ""
		(layer "F.Cu")
		(at 11.234166 -137.01776 180)
		(property "Reference" "PU22"
			(at 2.59207 -2.769108 0)
			(unlocked yes)
			(layer "F.SilkS")
			(effects
				(font
					(size 0.7874 0.5842)
					(thickness 0.1524)
				)
				(justify left)
			)
		)
		(property "Value" ""
			(at 0 0 180)
			(layer "F.Fab")
			(effects
				(font
					(size 1.27 1.27)
				)
			)
		)
		(duplicate_pad_numbers_are_jumpers no)
		(fp_line
			(start 1.943608 1.549908)
			(end -1.943608 1.549908)
			(stroke
				(width 0.1524)
				(type default)
			)
			(layer "F.SilkS")
		)
		(fp_line
			(start 1.943608 -1.549908)
			(end 1.943608 1.549908)
			(stroke
				(width 0.1524)
				(type default)
			)
			(layer "F.SilkS")
		)
		(fp_line
			(start -1.943608 1.549908)
			(end -1.943608 -1.549908)
			(stroke
				(width 0.1524)
				(type default)
			)
			(layer "F.SilkS")
		)
		(fp_line
			(start -1.943608 -1.549908)
			(end 1.943608 -1.549908)
			(stroke
				(width 0.1524)
				(type default)
			)
			(layer "F.SilkS")
		)
		(fp_poly
			(pts
				(xy -2.019808 -1.549908) (xy -1.257808 -1.549908) (xy -1.257808 -1.880108) (xy -2.019808 -1.880108)
			)
			(stroke
				(width 0)
				(type default)
			)
			(fill yes)
			(layer "F.SilkS")
		)
		(fp_line
			(start 1.549908 1.549908)
			(end -1.549908 1.549908)
			(stroke
				(width 0.1)
				(type default)
			)
			(layer "F.Fab")
		)
		(fp_line
			(start 1.549908 -1.549908)
			(end 1.549908 1.549908)
			(stroke
				(width 0.1)
				(type default)
			)
			(layer "F.Fab")
		)
		(fp_line
			(start -1.549908 1.549908)
			(end -1.549908 -1.549908)
			(stroke
				(width 0.1)
				(type default)
			)
			(layer "F.Fab")
		)
		(fp_line
			(start -1.549908 -1.549908)
			(end 1.549908 -1.549908)
			(stroke
				(width 0.1)
				(type default)
			)
			(layer "F.Fab")
		)
		(fp_poly
			(pts
				(xy -2.019808 -1.549908) (xy -1.257808 -1.549908) (xy -1.257808 -1.880108) (xy -2.019808 -1.880108)
			)
			(stroke
				(width 0)
				(type default)
			)
			(fill yes)
			(layer "F.Fab")
		)
		(pad "1" smd rect
			(at -1.500124 -1.249934 90)
			(size 0.2794 0.6096)
			(layers "F.Cu" "F.Mask" "F.Paste")
			(net "P12V_NIC0_R")
		)
		(pad "2" smd rect
			(at -1.500124 -0.750062 90)
			(size 0.2794 0.6096)
			(layers "F.Cu" "F.Mask" "F.Paste")
			(net "P12V_NIC0_R")
		)
		(pad "3" smd rect
			(at -1.500124 -0.249936 90)
			(size 0.2794 0.6096)
			(layers "F.Cu" "F.Mask" "F.Paste")
			(net "P12V_NIC0_R")
		)
		(pad "4" smd rect
			(at -1.500124 0.249936 90)
			(size 0.2794 0.6096)
			(layers "F.Cu" "F.Mask" "F.Paste")
			(net "P12V_NIC0_R")
		)
		(pad "5" smd rect
			(at -1.500124 0.750062 90)
			(size 0.2794 0.6096)
			(layers "F.Cu" "F.Mask" "F.Paste")
			(net "P12V_NIC0_R")
		)
		(pad "6" smd rect
			(at -1.500124 1.249934 90)
			(size 0.2794 0.6096)
			(layers "F.Cu" "F.Mask" "F.Paste")
			(net "GND")
		)
		(pad "7" smd rect
			(at 1.500124 1.249934 90)
			(size 0.2794 0.6096)
			(layers "F.Cu" "F.Mask" "F.Paste")
			(net "P12V_NIC0_SS")
		)
		(pad "8" smd rect
			(at 1.500124 0.750062 90)
			(size 0.2794 0.6096)
			(layers "F.Cu" "F.Mask" "F.Paste")
			(net "PWRGD_P12V_NIC0")
		)
		(pad "9" smd rect
			(at 1.500124 0.249936 90)
			(size 0.2794 0.6096)
			(layers "F.Cu" "F.Mask" "F.Paste")
			(net "P12V_NIC0_OCP")
		)
		(pad "10" smd rect
			(at 1.500124 -0.249936 90)
			(size 0.2794 0.6096)
			(layers "F.Cu" "F.Mask" "F.Paste")
			(net "P5V_AUX")
		)
		(pad "11" smd rect
			(at 1.500124 -0.750062 90)
			(size 0.2794 0.6096)
			(layers "F.Cu" "F.Mask" "F.Paste")
			(net "P12V_NIC0_EN_R")
		)
		(pad "12" smd rect
			(at 1.500124 -1.249934 90)
			(size 0.2794 0.6096)
			(layers "F.Cu" "F.Mask" "F.Paste")
			(net "P12V_AUX")
		)
		(pad "13" smd rect
			(at 0 0 180)
			(size 1.9812 2.7178)
			(layers "F.Cu" "F.Mask" "F.Paste")
			(net "P12V_AUX")
		)
		(zone
			(layer "F.Cu")
			(hatch none 0.5)
			(connect_pads
				(clearance 0)
			)
			(min_thickness 0.25)
			(keepout
				(tracks not_allowed)
				(vias allowed)
				(pads allowed)
				(copperpour not_allowed)
				(footprints allowed)
			)
			(placement
				(enabled no)
				(sheetname "")
			)
			(fill
				(thermal_gap 0.5)
				(thermal_bridge_width 0.5)
				(island_removal_mode 0)
			)
			(polygon
				(pts
					(xy 10.091166 -135.46836) (xy 10.091166 -135.59536) (xy 10.091166 -138.56716) (xy 10.091166 -138.567668)
					(xy 12.377166 -138.567668) (xy 12.377166 -138.56716) (xy 12.377166 -138.44016) (xy 12.377166 -137.01776)
					(xy 12.275566 -137.01776) (xy 12.275566 -138.44016) (xy 10.192766 -138.44016) (xy 10.192766 -135.59536)
					(xy 12.275566 -135.59536) (xy 12.275566 -136.99236) (xy 12.377166 -136.99236) (xy 12.377166 -135.59536)
					(xy 12.377166 -135.46836) (xy 12.377166 -135.467852) (xy 10.091166 -135.467852)
				)
			)
		)
	)
	(footprint ""
		(layer "F.Cu")
		(at 240.24971 -157.812994)
		(property "Reference" "R951"
			(at 0 0 0)
			(layer "F.SilkS")
			(hide yes)
			(effects
				(font
					(size 1.27 1.27)
				)
			)
		)
		(property "Value" ""
			(at 0 0 0)
			(layer "F.Fab")
			(effects
				(font
					(size 1.27 1.27)
				)
			)
		)
		(duplicate_pad_numbers_are_jumpers no)
		(fp_line
			(start -0.7874 -0.4064)
			(end 0.7874 -0.4064)
			(stroke
				(width 0.1524)
				(type default)
			)
			(layer "F.SilkS")
		)
		(fp_line
			(start -0.7874 0.4064)
			(end -0.7874 -0.4064)
			(stroke
				(width 0.1524)
				(type default)
			)
			(layer "F.SilkS")
		)
		(fp_line
			(start 0.7874 -0.4064)
			(end 0.7874 0.4064)
			(stroke
				(width 0.1524)
				(type default)
			)
			(layer "F.SilkS")
		)
		(fp_line
			(start 0.7874 0.4064)
			(end -0.7874 0.4064)
			(stroke
				(width 0.1524)
				(type default)
			)
			(layer "F.SilkS")
		)
		(fp_line
			(start -0.67945 -0.305054)
			(end -0.12065 -0.305054)
			(stroke
				(width 0.1)
				(type default)
			)
			(layer "F.Fab")
		)
		(fp_line
			(start -0.67945 0.3048)
			(end -0.67945 -0.305054)
			(stroke
				(width 0.1)
				(type default)
			)
			(layer "F.Fab")
		)
		(fp_line
			(start -0.12065 -0.305054)
			(end -0.12065 -0.2794)
			(stroke
				(width 0.1)
				(type default)
			)
			(layer "F.Fab")
		)
		(fp_line
			(start -0.12065 -0.2794)
			(end 0.12065 -0.2794)
			(stroke
				(width 0.1)
				(type default)
			)
			(layer "F.Fab")
		)
		(fp_line
			(start -0.12065 0.2794)
			(end -0.12065 0.3048)
			(stroke
				(width 0.1)
				(type default)
			)
			(layer "F.Fab")
		)
		(fp_line
			(start -0.12065 0.3048)
			(end -0.67945 0.3048)
			(stroke
				(width 0.1)
				(type default)
			)
			(layer "F.Fab")
		)
		(fp_line
			(start 0.120396 0.2794)
			(end -0.12065 0.2794)
			(stroke
				(width 0.1)
				(type default)
			)
			(layer "F.Fab")
		)
		(fp_line
			(start 0.120396 0.3048)
			(end 0.120396 0.2794)
			(stroke
				(width 0.1)
				(type default)
			)
			(layer "F.Fab")
		)
		(fp_line
			(start 0.12065 -0.3048)
			(end 0.67945 -0.3048)
			(stroke
				(width 0.1)
				(type default)
			)
			(layer "F.Fab")
		)
		(fp_line
			(start 0.12065 -0.2794)
			(end 0.12065 -0.3048)
			(stroke
				(width 0.1)
				(type default)
			)
			(layer "F.Fab")
		)
		(fp_line
			(start 0.67945 -0.3048)
			(end 0.67945 0.3048)
			(stroke
				(width 0.1)
				(type default)
			)
			(layer "F.Fab")
		)
		(fp_line
			(start 0.67945 0.3048)
			(end 0.120396 0.3048)
			(stroke
				(width 0.1)
				(type default)
			)
			(layer "F.Fab")
		)
		(pad "1" smd circle
			(at -0.40005 0)
			(size 0 0)
			(layers "F.Cu" "F.Mask" "F.Paste")
			(net "P3V3_AUX")
		)
		(pad "2" smd circle
			(at 0.40005 0)
			(size 0 0)
			(layers "F.Cu" "F.Mask" "F.Paste")
			(net "PWRGD_P12V_NIC4_CO")
		)
	)
	(footprint ""
		(layer "F.Cu")
		(at 53.462428 -22.937216 90)
		(property "Reference" "R1642"
			(at 0 0 90)
			(layer "F.SilkS")
			(hide yes)
			(effects
				(font
					(size 1.27 1.27)
				)
			)
		)
		(property "Value" ""
			(at 0 0 90)
			(layer "F.Fab")
			(effects
				(font
					(size 1.27 1.27)
				)
			)
		)
		(duplicate_pad_numbers_are_jumpers no)
		(fp_line
			(start 0.7874 -0.4064)
			(end 0.7874 0.4064)
			(stroke
				(width 0.1524)
				(type default)
			)
			(layer "F.SilkS")
		)
		(fp_line
			(start -0.7874 -0.4064)
			(end 0.7874 -0.4064)
			(stroke
				(width 0.1524)
				(type default)
			)
			(layer "F.SilkS")
		)
		(fp_line
			(start 0.7874 0.4064)
			(end -0.7874 0.4064)
			(stroke
				(width 0.1524)
				(type default)
			)
			(layer "F.SilkS")
		)
		(fp_line
			(start -0.7874 0.4064)
			(end -0.7874 -0.4064)
			(stroke
				(width 0.1524)
				(type default)
			)
			(layer "F.SilkS")
		)
		(fp_line
			(start -0.12065 -0.305054)
			(end -0.12065 -0.2794)
			(stroke
				(width 0.1)
				(type default)
			)
			(layer "F.Fab")
		)
		(fp_line
			(start -0.67945 -0.305054)
			(end -0.12065 -0.305054)
			(stroke
				(width 0.1)
				(type default)
			)
			(layer "F.Fab")
		)
		(fp_line
			(start 0.67945 -0.3048)
			(end 0.67945 0.3048)
			(stroke
				(width 0.1)
				(type default)
			)
			(layer "F.Fab")
		)
		(fp_line
			(start 0.12065 -0.3048)
			(end 0.67945 -0.3048)
			(stroke
				(width 0.1)
				(type default)
			)
			(layer "F.Fab")
		)
		(fp_line
			(start 0.12065 -0.2794)
			(end 0.12065 -0.3048)
			(stroke
				(width 0.1)
				(type default)
			)
			(layer "F.Fab")
		)
		(fp_line
			(start -0.12065 -0.2794)
			(end 0.12065 -0.2794)
			(stroke
				(width 0.1)
				(type default)
			)
			(layer "F.Fab")
		)
		(fp_line
			(start 0.120396 0.2794)
			(end -0.12065 0.2794)
			(stroke
				(width 0.1)
				(type default)
			)
			(layer "F.Fab")
		)
		(fp_line
			(start -0.12065 0.2794)
			(end -0.12065 0.3048)
			(stroke
				(width 0.1)
				(type default)
			)
			(layer "F.Fab")
		)
		(fp_line
			(start 0.67945 0.3048)
			(end 0.120396 0.3048)
			(stroke
				(width 0.1)
				(type default)
			)
			(layer "F.Fab")
		)
		(fp_line
			(start 0.120396 0.3048)
			(end 0.120396 0.2794)
			(stroke
				(width 0.1)
				(type default)
			)
			(layer "F.Fab")
		)
		(fp_line
			(start -0.12065 0.3048)
			(end -0.67945 0.3048)
			(stroke
				(width 0.1)
				(type default)
			)
			(layer "F.Fab")
		)
		(fp_line
			(start -0.67945 0.3048)
			(end -0.67945 -0.305054)
			(stroke
				(width 0.1)
				(type default)
			)
			(layer "F.Fab")
		)
		(pad "1" smd circle
			(at -0.40005 0 90)
			(size 0 0)
			(layers "F.Cu" "F.Mask" "F.Paste")
			(net "SMB_BIC_I2C9_MUX0_SSD1_R_SDA")
		)
		(pad "2" smd circle
			(at 0.40005 0 90)
			(size 0 0)
			(layers "F.Cu" "F.Mask" "F.Paste")
			(net "SMB_ISO_SSD1_SDA")
		)
	)
	(footprint ""
		(layer "F.Cu")
		(at 217.235786 -225.490786 180)
		(property "Reference" "R1486"
			(at 0 0 180)
			(layer "F.SilkS")
			(hide yes)
			(effects
				(font
					(size 1.27 1.27)
				)
			)
		)
		(property "Value" ""
			(at 0 0 180)
			(layer "F.Fab")
			(effects
				(font
					(size 1.27 1.27)
				)
			)
		)
		(duplicate_pad_numbers_are_jumpers no)
		(fp_line
			(start 0.7874 0.4064)
			(end -0.7874 0.4064)
			(stroke
				(width 0.1524)
				(type default)
			)
			(layer "F.SilkS")
		)
		(fp_line
			(start 0.7874 -0.4064)
			(end 0.7874 0.4064)
			(stroke
				(width 0.1524)
				(type default)
			)
			(layer "F.SilkS")
		)
		(fp_line
			(start -0.7874 0.4064)
			(end -0.7874 -0.4064)
			(stroke
				(width 0.1524)
				(type default)
			)
			(layer "F.SilkS")
		)
		(fp_line
			(start -0.7874 -0.4064)
			(end 0.7874 -0.4064)
			(stroke
				(width 0.1524)
				(type default)
			)
			(layer "F.SilkS")
		)
		(fp_line
			(start 0.67945 0.3048)
			(end 0.120396 0.3048)
			(stroke
				(width 0.1)
				(type default)
			)
			(layer "F.Fab")
		)
		(fp_line
			(start 0.67945 -0.3048)
			(end 0.67945 0.3048)
			(stroke
				(width 0.1)
				(type default)
			)
			(layer "F.Fab")
		)
		(fp_line
			(start 0.12065 -0.2794)
			(end 0.12065 -0.3048)
			(stroke
				(width 0.1)
				(type default)
			)
			(layer "F.Fab")
		)
		(fp_line
			(start 0.12065 -0.3048)
			(end 0.67945 -0.3048)
			(stroke
				(width 0.1)
				(type default)
			)
			(layer "F.Fab")
		)
		(fp_line
			(start 0.120396 0.3048)
			(end 0.120396 0.2794)
			(stroke
				(width 0.1)
				(type default)
			)
			(layer "F.Fab")
		)
		(fp_line
			(start 0.120396 0.2794)
			(end -0.12065 0.2794)
			(stroke
				(width 0.1)
				(type default)
			)
			(layer "F.Fab")
		)
		(fp_line
			(start -0.12065 0.3048)
			(end -0.67945 0.3048)
			(stroke
				(width 0.1)
				(type default)
			)
			(layer "F.Fab")
		)
		(fp_line
			(start -0.12065 0.2794)
			(end -0.12065 0.3048)
			(stroke
				(width 0.1)
				(type default)
			)
			(layer "F.Fab")
		)
		(fp_line
			(start -0.12065 -0.2794)
			(end 0.12065 -0.2794)
			(stroke
				(width 0.1)
				(type default)
			)
			(layer "F.Fab")
		)
		(fp_line
			(start -0.12065 -0.305054)
			(end -0.12065 -0.2794)
			(stroke
				(width 0.1)
				(type default)
			)
			(layer "F.Fab")
		)
		(fp_line
			(start -0.67945 0.3048)
			(end -0.67945 -0.305054)
			(stroke
				(width 0.1)
				(type default)
			)
			(layer "F.Fab")
		)
		(fp_line
			(start -0.67945 -0.305054)
			(end -0.12065 -0.305054)
			(stroke
				(width 0.1)
				(type default)
			)
			(layer "F.Fab")
		)
		(pad "1" smd circle
			(at -0.40005 0 180)
			(size 0 0)
			(layers "F.Cu" "F.Mask" "F.Paste")
			(net "SMB_NIC3_SCL")
		)
		(pad "2" smd circle
			(at 0.40005 0 180)
			(size 0 0)
			(layers "F.Cu" "F.Mask" "F.Paste")
			(net "SMB_NIC3_R_SCL")
		)
	)
	(footprint ""
		(layer "F.Cu")
		(at 387.06044 -97.1804 180)
		(property "Reference" "R314"
			(at 0 0 180)
			(layer "F.SilkS")
			(hide yes)
			(effects
				(font
					(size 1.27 1.27)
				)
			)
		)
		(property "Value" ""
			(at 0 0 180)
			(layer "F.Fab")
			(effects
				(font
					(size 1.27 1.27)
				)
			)
		)
		(duplicate_pad_numbers_are_jumpers no)
		(fp_line
			(start 0.7874 0.4064)
			(end -0.7874 0.4064)
			(stroke
				(width 0.1524)
				(type default)
			)
			(layer "F.SilkS")
		)
		(fp_line
			(start 0.7874 -0.4064)
			(end 0.7874 0.4064)
			(stroke
				(width 0.1524)
				(type default)
			)
			(layer "F.SilkS")
		)
		(fp_line
			(start -0.7874 0.4064)
			(end -0.7874 -0.4064)
			(stroke
				(width 0.1524)
				(type default)
			)
			(layer "F.SilkS")
		)
		(fp_line
			(start -0.7874 -0.4064)
			(end 0.7874 -0.4064)
			(stroke
				(width 0.1524)
				(type default)
			)
			(layer "F.SilkS")
		)
		(fp_line
			(start 0.67945 0.3048)
			(end 0.120396 0.3048)
			(stroke
				(width 0.1)
				(type default)
			)
			(layer "F.Fab")
		)
		(fp_line
			(start 0.67945 -0.3048)
			(end 0.67945 0.3048)
			(stroke
				(width 0.1)
				(type default)
			)
			(layer "F.Fab")
		)
		(fp_line
			(start 0.12065 -0.2794)
			(end 0.12065 -0.3048)
			(stroke
				(width 0.1)
				(type default)
			)
			(layer "F.Fab")
		)
		(fp_line
			(start 0.12065 -0.3048)
			(end 0.67945 -0.3048)
			(stroke
				(width 0.1)
				(type default)
			)
			(layer "F.Fab")
		)
		(fp_line
			(start 0.120396 0.3048)
			(end 0.120396 0.2794)
			(stroke
				(width 0.1)
				(type default)
			)
			(layer "F.Fab")
		)
		(fp_line
			(start 0.120396 0.2794)
			(end -0.12065 0.2794)
			(stroke
				(width 0.1)
				(type default)
			)
			(layer "F.Fab")
		)
		(fp_line
			(start -0.12065 0.3048)
			(end -0.67945 0.3048)
			(stroke
				(width 0.1)
				(type default)
			)
			(layer "F.Fab")
		)
		(fp_line
			(start -0.12065 0.2794)
			(end -0.12065 0.3048)
			(stroke
				(width 0.1)
				(type default)
			)
			(layer "F.Fab")
		)
		(fp_line
			(start -0.12065 -0.2794)
			(end 0.12065 -0.2794)
			(stroke
				(width 0.1)
				(type default)
			)
			(layer "F.Fab")
		)
		(fp_line
			(start -0.12065 -0.305054)
			(end -0.12065 -0.2794)
			(stroke
				(width 0.1)
				(type default)
			)
			(layer "F.Fab")
		)
		(fp_line
			(start -0.67945 0.3048)
			(end -0.67945 -0.305054)
			(stroke
				(width 0.1)
				(type default)
			)
			(layer "F.Fab")
		)
		(fp_line
			(start -0.67945 -0.305054)
			(end -0.12065 -0.305054)
			(stroke
				(width 0.1)
				(type default)
			)
			(layer "F.Fab")
		)
		(pad "1" smd circle
			(at -0.40005 0 180)
			(size 0 0)
			(layers "F.Cu" "F.Mask" "F.Paste")
			(net "PRSNTB3_NIC6_N")
		)
		(pad "2" smd circle
			(at 0.40005 0 180)
			(size 0 0)
			(layers "F.Cu" "F.Mask" "F.Paste")
			(net "P3V3_AUX")
		)
	)
	(footprint ""
		(layer "F.Cu")
		(at 132.088128 -45.704252 90)
		(property "Reference" "R551"
			(at 0 0 90)
			(layer "F.SilkS")
			(hide yes)
			(effects
				(font
					(size 1.27 1.27)
				)
			)
		)
		(property "Value" ""
			(at 0 0 90)
			(layer "F.Fab")
			(effects
				(font
					(size 1.27 1.27)
				)
			)
		)
		(duplicate_pad_numbers_are_jumpers no)
		(fp_line
			(start 3.937508 -1.8796)
			(end -3.937508 -1.8796)
			(stroke
				(width 0.1524)
				(type default)
			)
			(layer "F.SilkS")
		)
		(fp_line
			(start -3.937508 -1.8796)
			(end -3.937508 1.8796)
			(stroke
				(width 0.1524)
				(type default)
			)
			(layer "F.SilkS")
		)
		(fp_line
			(start 3.937508 1.8796)
			(end 3.937508 -1.8796)
			(stroke
				(width 0.1524)
				(type default)
			)
			(layer "F.SilkS")
		)
		(fp_line
			(start -3.937508 1.8796)
			(end 3.937508 1.8796)
			(stroke
				(width 0.1524)
				(type default)
			)
			(layer "F.SilkS")
		)
		(fp_line
			(start 3.275076 -1.674876)
			(end -3.275076 -1.674876)
			(stroke
				(width 0.1)
				(type default)
			)
			(layer "F.Fab")
		)
		(fp_line
			(start -3.275076 -1.674876)
			(end -3.275076 1.674876)
			(stroke
				(width 0.1)
				(type default)
			)
			(layer "F.Fab")
		)
		(fp_line
			(start 3.275076 1.674876)
			(end 3.275076 -1.674876)
			(stroke
				(width 0.1)
				(type default)
			)
			(layer "F.Fab")
		)
		(fp_line
			(start -3.275076 1.674876)
			(end 3.275076 1.674876)
			(stroke
				(width 0.1)
				(type default)
			)
			(layer "F.Fab")
		)
		(pad "1" smd rect
			(at -2.350008 0 90)
			(size 2.921 3.5052)
			(layers "F.Cu" "F.Mask" "F.Paste")
			(net "P12V_SSD4")
		)
		(pad "2" smd rect
			(at 2.350008 0 90)
			(size 2.921 3.5052)
			(layers "F.Cu" "F.Mask" "F.Paste")
			(net "P12V_SSD4_R")
		)
	)
)
